# S9S_MB_2U (Grand Teton) — schematic netlist excerpt (pin names and nets, part order shuffled) for the footprints in the layout excerpt that follows; sources: Cadence DE-HDL packaged netlist, KiCad conversion of 03242023_DA0F0TMBIJ0_F0T_Motherboard_J_brd_V01_OCP.brd

R3454  Q_RES  1K 1% CHIP  pkg 0402LF  page 149 : A = GPU_FPGA_BOOT_EN_BUF_R ; B = GND
PC507_P1_6  Q_CAP  1UF 16V 10% X6S  pkg C0402  page 287 : A = SW_P12V_PVCCIN_CPU1_FLT ; B = GND

(kicad_pcb
	(version 20260206)
	(generator "pcbnew")
	(generator_version "10.0")
	(general
		(thickness 1.6)
		(legacy_teardrops no)
	)
	(paper "A4")
	(title_block
		(title "03242023_DA0F0TMBIJ0_F0T_Motherboard_J_brd_V01_OCP.brd")
		(comment 1 "Grand Teton / footprints 2746-2747 of 6105")
	)
	(layers
		(0 "F.Cu" signal "TOP")
		(4 "In1.Cu" signal "GND")
		(6 "In2.Cu" signal "IN1")
		(8 "In3.Cu" signal "GND1")
		(10 "In4.Cu" signal "IN2")
		(12 "In5.Cu" signal "GND2")
		(14 "In6.Cu" signal "IN3")
		(16 "In7.Cu" signal "GND3")
		(18 "In8.Cu" signal "VCC")
		(20 "In9.Cu" signal "VCC1")
		(22 "In10.Cu" signal "GND4")
		(24 "In11.Cu" signal "IN4")
		(26 "In12.Cu" signal "GND5")
		(28 "In13.Cu" signal "IN5")
		(30 "In14.Cu" signal "GND6")
		(32 "In15.Cu" signal "IN6")
		(34 "In16.Cu" signal "GND7")
		(2 "B.Cu" signal "BOTTOM")
		(9 "F.Adhes" user "F.Adhesive")
		(11 "B.Adhes" user "B.Adhesive")
		(13 "F.Paste" user "Package Geometry/Pastemask Top")
		(15 "B.Paste" user "Package Geometry/Pastemask Bottom")
		(5 "F.SilkS" user "Ref Des/Silkscreen Top")
		(7 "B.SilkS" user "Ref Des/Silkscreen Bottom")
		(1 "F.Mask" user "Board Geometry/Soldermask Top")
		(3 "B.Mask" user "Board Geometry/Soldermask Bottom")
		(17 "Dwgs.User" user "User.Drawings")
		(19 "Cmts.User" user "User.Comments")
		(21 "Eco1.User" user "User.Eco1")
		(23 "Eco2.User" user "User.Eco2")
		(25 "Edge.Cuts" user "Board Geometry/Outline")
		(27 "Margin" user)
		(31 "F.CrtYd" user "Package Geometry/Place Bound Top")
		(29 "B.CrtYd" user "Package Geometry/Place Bound Bottom")
		(35 "F.Fab" user "Ref Des/Assembly Top")
		(33 "B.Fab" user "Ref Des/Assembly Bottom")
	)
	(footprint ""
		(layer "F.Cu")
		(at 170.23588 -440.019948)
		(property "Reference" "R3454"
			(at 0 0 0)
			(layer "F.SilkS")
			(hide yes)
			(effects
				(font
					(size 1.27 1.27)
				)
			)
		)
		(property "Value" ""
			(at 0 0 0)
			(layer "F.Fab")
			(effects
				(font
					(size 1.27 1.27)
				)
			)
		)
		(duplicate_pad_numbers_are_jumpers no)
		(fp_line
			(start -0.7874 -0.4064)
			(end 0.7874 -0.4064)
			(stroke
				(width 0.1524)
				(type default)
			)
			(layer "F.SilkS")
		)
		(fp_line
			(start -0.7874 0.4064)
			(end -0.7874 -0.4064)
			(stroke
				(width 0.1524)
				(type default)
			)
			(layer "F.SilkS")
		)
		(fp_line
			(start 0.7874 -0.4064)
			(end 0.7874 0.4064)
			(stroke
				(width 0.1524)
				(type default)
			)
			(layer "F.SilkS")
		)
		(fp_line
			(start 0.7874 0.4064)
			(end -0.7874 0.4064)
			(stroke
				(width 0.1524)
				(type default)
			)
			(layer "F.SilkS")
		)
		(fp_line
			(start -0.67945 -0.305054)
			(end -0.12065 -0.305054)
			(stroke
				(width 0.1)
				(type default)
			)
			(layer "F.Fab")
		)
		(fp_line
			(start -0.67945 0.3048)
			(end -0.67945 -0.305054)
			(stroke
				(width 0.1)
				(type default)
			)
			(layer "F.Fab")
		)
		(fp_line
			(start -0.12065 -0.305054)
			(end -0.12065 -0.2794)
			(stroke
				(width 0.1)
				(type default)
			)
			(layer "F.Fab")
		)
		(fp_line
			(start -0.12065 -0.2794)
			(end 0.12065 -0.2794)
			(stroke
				(width 0.1)
				(type default)
			)
			(layer "F.Fab")
		)
		(fp_line
			(start -0.12065 0.2794)
			(end -0.12065 0.3048)
			(stroke
				(width 0.1)
				(type default)
			)
			(layer "F.Fab")
		)
		(fp_line
			(start -0.12065 0.3048)
			(end -0.67945 0.3048)
			(stroke
				(width 0.1)
				(type default)
			)
			(layer "F.Fab")
		)
		(fp_line
			(start 0.120396 0.2794)
			(end -0.12065 0.2794)
			(stroke
				(width 0.1)
				(type default)
			)
			(layer "F.Fab")
		)
		(fp_line
			(start 0.120396 0.3048)
			(end 0.120396 0.2794)
			(stroke
				(width 0.1)
				(type default)
			)
			(layer "F.Fab")
		)
		(fp_line
			(start 0.12065 -0.3048)
			(end 0.67945 -0.3048)
			(stroke
				(width 0.1)
				(type default)
			)
			(layer "F.Fab")
		)
		(fp_line
			(start 0.12065 -0.2794)
			(end 0.12065 -0.3048)
			(stroke
				(width 0.1)
				(type default)
			)
			(layer "F.Fab")
		)
		(fp_line
			(start 0.67945 -0.3048)
			(end 0.67945 0.3048)
			(stroke
				(width 0.1)
				(type default)
			)
			(layer "F.Fab")
		)
		(fp_line
			(start 0.67945 0.3048)
			(end 0.120396 0.3048)
			(stroke
				(width 0.1)
				(type default)
			)
			(layer "F.Fab")
		)
		(pad "1" smd circle
			(at -0.40005 0)
			(size 0 0)
			(layers "F.Cu" "F.Mask" "F.Paste")
			(net "GPU_FPGA_BOOT_EN_BUF_R")
		)
		(pad "2" smd circle
			(at 0.40005 0)
			(size 0 0)
			(layers "F.Cu" "F.Mask" "F.Paste")
			(net "GND")
		)
	)
	(footprint ""
		(layer "F.Cu")
		(at 92.40647 -337.214718 -90)
		(property "Reference" "PC507_P1_6"
			(at 0 0 270)
			(layer "F.SilkS")
			(hide yes)
			(effects
				(font
					(size 1.27 1.27)
				)
			)
		)
		(property "Value" ""
			(at 0 0 270)
			(layer "F.Fab")
			(effects
				(font
					(size 1.27 1.27)
				)
			)
		)
		(duplicate_pad_numbers_are_jumpers no)
		(fp_line
			(start -0.7874 0.4064)
			(end -0.7874 -0.4064)
			(stroke
				(width 0.1524)
				(type default)
			)
			(layer "F.SilkS")
		)
		(fp_line
			(start 0.7874 0.4064)
			(end -0.7874 0.4064)
			(stroke
				(width 0.1524)
				(type default)
			)
			(layer "F.SilkS")
		)
		(fp_line
			(start -0.7874 -0.4064)
			(end 0.7874 -0.4064)
			(stroke
				(width 0.1524)
				(type default)
			)
			(layer "F.SilkS")
		)
		(fp_line
			(start 0.7874 -0.4064)
			(end 0.7874 0.4064)
			(stroke
				(width 0.1524)
				(type default)
			)
			(layer "F.SilkS")
		)
		(fp_line
			(start -0.67945 0.3048)
			(end -0.67945 -0.305054)
			(stroke
				(width 0.1)
				(type default)
			)
			(layer "F.Fab")
		)
		(fp_line
			(start -0.12065 0.3048)
			(end -0.67945 0.3048)
			(stroke
				(width 0.1)
				(type default)
			)
			(layer "F.Fab")
		)
		(fp_line
			(start 0.120396 0.3048)
			(end 0.120396 0.2794)
			(stroke
				(width 0.1)
				(type default)
			)
			(layer "F.Fab")
		)
		(fp_line
			(start 0.67945 0.3048)
			(end 0.120396 0.3048)
			(stroke
				(width 0.1)
				(type default)
			)
			(layer "F.Fab")
		)
		(fp_line
			(start -0.12065 0.2794)
			(end -0.12065 0.3048)
			(stroke
				(width 0.1)
				(type default)
			)
			(layer "F.Fab")
		)
		(fp_line
			(start 0.120396 0.2794)
			(end -0.12065 0.2794)
			(stroke
				(width 0.1)
				(type default)
			)
			(layer "F.Fab")
		)
		(fp_line
			(start -0.12065 -0.2794)
			(end 0.12065 -0.2794)
			(stroke
				(width 0.1)
				(type default)
			)
			(layer "F.Fab")
		)
		(fp_line
			(start 0.12065 -0.2794)
			(end 0.12065 -0.3048)
			(stroke
				(width 0.1)
				(type default)
			)
			(layer "F.Fab")
		)
		(fp_line
			(start 0.12065 -0.3048)
			(end 0.67945 -0.3048)
			(stroke
				(width 0.1)
				(type default)
			)
			(layer "F.Fab")
		)
		(fp_line
			(start 0.67945 -0.3048)
			(end 0.67945 0.3048)
			(stroke
				(width 0.1)
				(type default)
			)
			(layer "F.Fab")
		)
		(fp_line
			(start -0.67945 -0.305054)
			(end -0.12065 -0.305054)
			(stroke
				(width 0.1)
				(type default)
			)
			(layer "F.Fab")
		)
		(fp_line
			(start -0.12065 -0.305054)
			(end -0.12065 -0.2794)
			(stroke
				(width 0.1)
				(type default)
			)
			(layer "F.Fab")
		)
		(pad "1" smd circle
			(at -0.40005 0 270)
			(size 0 0)
			(layers "F.Cu" "F.Mask" "F.Paste")
			(net "SW_P12V_PVCCIN_CPU1_FLT")
		)
		(pad "2" smd circle
			(at 0.40005 0 270)
			(size 0 0)
			(layers "F.Cu" "F.Mask" "F.Paste")
			(net "GND")
		)
	)
)
